# SCM (Grand Teton) — schematic netlist excerpt (pin names and nets, part order shuffled) for the footprints in the layout excerpt that follows; sources: Cadence DE-HDL packaged netlist, KiCad conversion of 12092022_DA0F0TMDCD0_F0T_Management_Board_D_brd_V3_OCP.brd

R898  Q_RES  0 5% CHIP  pkg 0402LF  page 36 : A = FM_UARTSW_LSB_R_N ; B = FM_UARTSW_LSB_N
R728  Q_RES  0 5% CHIP  pkg 0402LF  page 44 : A = SPI_BMC_BIOS_CS0_N ; B = SPI_BMC_BIOS_SOURCE_CS0_N

(kicad_pcb
	(version 20260206)
	(generator "pcbnew")
	(generator_version "10.0")
	(general
		(thickness 1.6)
		(legacy_teardrops no)
	)
	(paper "A4")
	(title_block
		(title "12092022_DA0F0TMDCD0_F0T_Management_Board_D_brd_V3_OCP.brd")
		(comment 1 "Grand Teton / footprints 968-969 of 1440")
	)
	(layers
		(0 "F.Cu" signal "TOP")
		(4 "In1.Cu" signal "GND")
		(6 "In2.Cu" signal "IN1")
		(8 "In3.Cu" signal "GND1")
		(10 "In4.Cu" signal "IN2")
		(12 "In5.Cu" signal "VCC")
		(14 "In6.Cu" signal "VCC1")
		(16 "In7.Cu" signal "IN3")
		(18 "In8.Cu" signal "GND2")
		(20 "In9.Cu" signal "IN4")
		(22 "In10.Cu" signal "GND3")
		(2 "B.Cu" signal "BOTTOM")
		(9 "F.Adhes" user "F.Adhesive")
		(11 "B.Adhes" user "B.Adhesive")
		(13 "F.Paste" user "Package Geometry/Pastemask Top")
		(15 "B.Paste" user "Package Geometry/Pastemask Bottom")
		(5 "F.SilkS" user "Ref Des/Silkscreen Top")
		(7 "B.SilkS" user "Ref Des/Silkscreen Bottom")
		(1 "F.Mask" user "Board Geometry/Soldermask Top")
		(3 "B.Mask" user "Board Geometry/Soldermask Bottom")
		(17 "Dwgs.User" user "User.Drawings")
		(19 "Cmts.User" user "User.Comments")
		(21 "Eco1.User" user "User.Eco1")
		(23 "Eco2.User" user "User.Eco2")
		(25 "Edge.Cuts" user "Board Geometry/Outline")
		(27 "Margin" user)
		(31 "F.CrtYd" user "Package Geometry/Place Bound Top")
		(29 "B.CrtYd" user "Package Geometry/Place Bound Bottom")
		(35 "F.Fab" user "Ref Des/Assembly Top")
		(33 "B.Fab" user "Ref Des/Assembly Bottom")
	)
	(footprint ""
		(layer "B.Cu")
		(at 13.335 -106.426 90)
		(property "Reference" "R898"
			(at 0 0 90)
			(layer "B.SilkS")
			(hide yes)
			(effects
				(font
					(size 1.27 1.27)
				)
				(justify mirror)
			)
		)
		(property "Value" ""
			(at 0 0 90)
			(layer "B.Fab")
			(effects
				(font
					(size 1.27 1.27)
				)
				(justify mirror)
			)
		)
		(duplicate_pad_numbers_are_jumpers no)
		(fp_line
			(start 0.7874 -0.4064)
			(end -0.7874 -0.4064)
			(stroke
				(width 0.1524)
				(type default)
			)
			(layer "B.SilkS")
		)
		(fp_line
			(start -0.7874 -0.4064)
			(end -0.7874 0.4064)
			(stroke
				(width 0.1524)
				(type default)
			)
			(layer "B.SilkS")
		)
		(fp_line
			(start 0.7874 0.4064)
			(end 0.7874 -0.4064)
			(stroke
				(width 0.1524)
				(type default)
			)
			(layer "B.SilkS")
		)
		(fp_line
			(start -0.7874 0.4064)
			(end 0.7874 0.4064)
			(stroke
				(width 0.1524)
				(type default)
			)
			(layer "B.SilkS")
		)
		(fp_line
			(start 0.67945 -0.305054)
			(end 0.12065 -0.305054)
			(stroke
				(width 0.1)
				(type default)
			)
			(layer "B.Fab")
		)
		(fp_line
			(start 0.12065 -0.305054)
			(end 0.12065 -0.2794)
			(stroke
				(width 0.1)
				(type default)
			)
			(layer "B.Fab")
		)
		(fp_line
			(start -0.12065 -0.3048)
			(end -0.67945 -0.3048)
			(stroke
				(width 0.1)
				(type default)
			)
			(layer "B.Fab")
		)
		(fp_line
			(start -0.67945 -0.3048)
			(end -0.67945 0.3048)
			(stroke
				(width 0.1)
				(type default)
			)
			(layer "B.Fab")
		)
		(fp_line
			(start 0.12065 -0.2794)
			(end -0.12065 -0.2794)
			(stroke
				(width 0.1)
				(type default)
			)
			(layer "B.Fab")
		)
		(fp_line
			(start -0.12065 -0.2794)
			(end -0.12065 -0.3048)
			(stroke
				(width 0.1)
				(type default)
			)
			(layer "B.Fab")
		)
		(fp_line
			(start 0.12065 0.2794)
			(end 0.12065 0.3048)
			(stroke
				(width 0.1)
				(type default)
			)
			(layer "B.Fab")
		)
		(fp_line
			(start -0.120396 0.2794)
			(end 0.12065 0.2794)
			(stroke
				(width 0.1)
				(type default)
			)
			(layer "B.Fab")
		)
		(fp_line
			(start 0.67945 0.3048)
			(end 0.67945 -0.305054)
			(stroke
				(width 0.1)
				(type default)
			)
			(layer "B.Fab")
		)
		(fp_line
			(start 0.12065 0.3048)
			(end 0.67945 0.3048)
			(stroke
				(width 0.1)
				(type default)
			)
			(layer "B.Fab")
		)
		(fp_line
			(start -0.120396 0.3048)
			(end -0.120396 0.2794)
			(stroke
				(width 0.1)
				(type default)
			)
			(layer "B.Fab")
		)
		(fp_line
			(start -0.67945 0.3048)
			(end -0.120396 0.3048)
			(stroke
				(width 0.1)
				(type default)
			)
			(layer "B.Fab")
		)
		(pad "1" smd circle
			(at 0.40005 0 270)
			(size 0 0)
			(layers "B.Cu" "B.Mask" "B.Paste")
			(net "FM_UARTSW_LSB_R_N")
		)
		(pad "2" smd circle
			(at -0.40005 0 270)
			(size 0 0)
			(layers "B.Cu" "B.Mask" "B.Paste")
			(net "FM_UARTSW_LSB_N")
		)
	)
	(footprint ""
		(layer "B.Cu")
		(at 37.4015 -99.568 180)
		(property "Reference" "R728"
			(at 0 0 0)
			(layer "B.SilkS")
			(hide yes)
			(effects
				(font
					(size 1.27 1.27)
				)
				(justify mirror)
			)
		)
		(property "Value" ""
			(at 0 0 0)
			(layer "B.Fab")
			(effects
				(font
					(size 1.27 1.27)
				)
				(justify mirror)
			)
		)
		(duplicate_pad_numbers_are_jumpers no)
		(fp_line
			(start 0.7874 0.4064)
			(end 0.7874 -0.4064)
			(stroke
				(width 0.1524)
				(type default)
			)
			(layer "B.SilkS")
		)
		(fp_line
			(start 0.7874 -0.4064)
			(end -0.7874 -0.4064)
			(stroke
				(width 0.1524)
				(type default)
			)
			(layer "B.SilkS")
		)
		(fp_line
			(start -0.7874 0.4064)
			(end 0.7874 0.4064)
			(stroke
				(width 0.1524)
				(type default)
			)
			(layer "B.SilkS")
		)
		(fp_line
			(start -0.7874 -0.4064)
			(end -0.7874 0.4064)
			(stroke
				(width 0.1524)
				(type default)
			)
			(layer "B.SilkS")
		)
		(fp_line
			(start 0.67945 0.3048)
			(end 0.67945 -0.305054)
			(stroke
				(width 0.1)
				(type default)
			)
			(layer "B.Fab")
		)
		(fp_line
			(start 0.67945 -0.305054)
			(end 0.12065 -0.305054)
			(stroke
				(width 0.1)
				(type default)
			)
			(layer "B.Fab")
		)
		(fp_line
			(start 0.12065 0.3048)
			(end 0.67945 0.3048)
			(stroke
				(width 0.1)
				(type default)
			)
			(layer "B.Fab")
		)
		(fp_line
			(start 0.12065 0.2794)
			(end 0.12065 0.3048)
			(stroke
				(width 0.1)
				(type default)
			)
			(layer "B.Fab")
		)
		(fp_line
			(start 0.12065 -0.2794)
			(end -0.12065 -0.2794)
			(stroke
				(width 0.1)
				(type default)
			)
			(layer "B.Fab")
		)
		(fp_line
			(start 0.12065 -0.305054)
			(end 0.12065 -0.2794)
			(stroke
				(width 0.1)
				(type default)
			)
			(layer "B.Fab")
		)
		(fp_line
			(start -0.120396 0.3048)
			(end -0.120396 0.2794)
			(stroke
				(width 0.1)
				(type default)
			)
			(layer "B.Fab")
		)
		(fp_line
			(start -0.120396 0.2794)
			(end 0.12065 0.2794)
			(stroke
				(width 0.1)
				(type default)
			)
			(layer "B.Fab")
		)
		(fp_line
			(start -0.12065 -0.2794)
			(end -0.12065 -0.3048)
			(stroke
				(width 0.1)
				(type default)
			)
			(layer "B.Fab")
		)
		(fp_line
			(start -0.12065 -0.3048)
			(end -0.67945 -0.3048)
			(stroke
				(width 0.1)
				(type default)
			)
			(layer "B.Fab")
		)
		(fp_line
			(start -0.67945 0.3048)
			(end -0.120396 0.3048)
			(stroke
				(width 0.1)
				(type default)
			)
			(layer "B.Fab")
		)
		(fp_line
			(start -0.67945 -0.3048)
			(end -0.67945 0.3048)
			(stroke
				(width 0.1)
				(type default)
			)
			(layer "B.Fab")
		)
		(pad "1" smd circle
			(at 0.40005 0)
			(size 0 0)
			(layers "B.Cu" "B.Mask" "B.Paste")
			(net "SPI_BMC_BIOS_CS0_N")
		)
		(pad "2" smd circle
			(at -0.40005 0)
			(size 0 0)
			(layers "B.Cu" "B.Mask" "B.Paste")
			(net "SPI_BMC_BIOS_SOURCE_CS0_N")
		)
	)
)
